(kicad_pcb
	(version 20260206)
	(generator "pcbnew")
	(generator_version "10.0")
	(general
		(thickness 1.6)
		(legacy_teardrops no)
	)
	(paper "A4")
	(title_block
		(title "Wiwynn_Tioga_Pass_MB.brd")
		(comment 1 "Tioga Pass / footprints 2440-2444 of 4770")
	)
	(layers
		(0 "F.Cu" signal "TOP")
		(4 "In1.Cu" signal "L2GND")
		(6 "In2.Cu" signal "L3")
		(8 "In3.Cu" signal "L4GND")
		(10 "In4.Cu" signal "L5")
		(12 "In5.Cu" signal "L6GND")
		(14 "In6.Cu" signal "L7VCC")
		(16 "In7.Cu" signal "L8VCC")
		(18 "In8.Cu" signal "L9GND")
		(20 "In9.Cu" signal "L10")
		(22 "In10.Cu" signal "L11GND")
		(24 "In11.Cu" signal "L12")
		(26 "In12.Cu" signal "L13GND")
		(2 "B.Cu" signal "BOTTOM")
		(9 "F.Adhes" user "F.Adhesive")
		(11 "B.Adhes" user "B.Adhesive")
		(13 "F.Paste" user "Package Geometry/Pastemask Top")
		(15 "B.Paste" user "Package Geometry/Pastemask Bottom")
		(5 "F.SilkS" user "Ref Des/Silkscreen Top")
		(7 "B.SilkS" user "Ref Des/Silkscreen Bottom")
		(1 "F.Mask" user "Board Geometry/Soldermask Top")
		(3 "B.Mask" user "Board Geometry/Soldermask Bottom")
		(17 "Dwgs.User" user "User.Drawings")
		(19 "Cmts.User" user "User.Comments")
		(21 "Eco1.User" user "User.Eco1")
		(23 "Eco2.User" user "User.Eco2")
		(25 "Edge.Cuts" user "Board Geometry/Outline")
		(27 "Margin" user)
		(31 "F.CrtYd" user "Package Geometry/Place Bound Top")
		(29 "B.CrtYd" user "Package Geometry/Place Bound Bottom")
		(35 "F.Fab" user "Ref Des/Assembly Top")
		(33 "B.Fab" user "Ref Des/Assembly Bottom")
	)
	(footprint ""
		(layer "B.Cu")
		(at 110.007654 -77.82814)
		(property "Reference" "C7P9"
			(at 0 0 0)
			(layer "B.SilkS")
			(hide yes)
			(effects
				(font
					(size 1.27 1.27)
				)
				(justify mirror)
			)
		)
		(property "Value" ""
			(at 0 0 0)
			(layer "B.Fab")
			(effects
				(font
					(size 1.27 1.27)
				)
				(justify mirror)
			)
		)
		(duplicate_pad_numbers_are_jumpers no)
		(fp_poly
			(pts
				(xy 0.7239 -0.2159) (xy -0.7239 -0.2159) (xy -0.7239 1.9939) (xy 0.7239 1.9939)
			)
			(stroke
				(width 0)
				(type default)
			)
			(fill no)
			(layer "B.CrtYd")
		)
		(fp_line
			(start -0.7239 -0.2159)
			(end 0.7239 -0.2159)
			(stroke
				(width 0.1)
				(type default)
			)
			(layer "B.Fab")
		)
		(fp_line
			(start -0.7239 1.9939)
			(end -0.7239 -0.2159)
			(stroke
				(width 0.1)
				(type default)
			)
			(layer "B.Fab")
		)
		(fp_line
			(start 0.7239 -0.2159)
			(end 0.7239 1.9939)
			(stroke
				(width 0.1)
				(type default)
			)
			(layer "B.Fab")
		)
		(fp_line
			(start 0.7239 1.9939)
			(end -0.7239 1.9939)
			(stroke
				(width 0.1)
				(type default)
			)
			(layer "B.Fab")
		)
		(pad "1" smd rect
			(at 0 0 180)
			(size 1.27 1.016)
			(layers "B.Cu" "B.Mask" "B.Paste")
			(net "PVCCMCP_CPU1")
		)
		(pad "2" smd rect
			(at 0 1.778 180)
			(size 1.27 1.016)
			(layers "B.Cu" "B.Mask" "B.Paste")
			(net "GND")
		)
		(zone
			(layer "B.Cu")
			(hatch none 0.5)
			(connect_pads
				(clearance 0)
			)
			(min_thickness 0.25)
			(keepout
				(tracks not_allowed)
				(vias allowed)
				(pads allowed)
				(copperpour not_allowed)
				(footprints allowed)
			)
			(placement
				(enabled no)
				(sheetname "")
			)
			(fill
				(thermal_gap 0.5)
				(thermal_bridge_width 0.5)
				(island_removal_mode 0)
			)
			(polygon
				(pts
					(xy 110.642654 -77.32014) (xy 109.372654 -77.32014) (xy 109.372654 -76.55814) (xy 110.642654 -76.55814)
				)
			)
		)
	)
	(footprint ""
		(layer "B.Cu")
		(at 408.1272 -122.0216 90)
		(property "Reference" "FB2M2"
			(at 0 0 90)
			(layer "B.SilkS")
			(hide yes)
			(effects
				(font
					(size 1.27 1.27)
				)
				(justify mirror)
			)
		)
		(property "Value" ""
			(at 0 0 90)
			(layer "B.Fab")
			(effects
				(font
					(size 1.27 1.27)
				)
				(justify mirror)
			)
		)
		(duplicate_pad_numbers_are_jumpers no)
		(fp_poly
			(pts
				(xy 0.15113 -0.47498) (xy -1.59893 -0.47498) (xy -1.59893 0.47498) (xy 0.15113 0.47498)
			)
			(stroke
				(width 0)
				(type default)
			)
			(fill no)
			(layer "B.CrtYd")
		)
		(fp_line
			(start 0.15113 -0.47498)
			(end -1.59893 -0.47498)
			(stroke
				(width 0.1)
				(type default)
			)
			(layer "B.Fab")
		)
		(fp_line
			(start -1.59893 -0.47498)
			(end -1.59893 0.47498)
			(stroke
				(width 0.1)
				(type default)
			)
			(layer "B.Fab")
		)
		(fp_line
			(start 0.15113 0.47498)
			(end 0.15113 -0.47498)
			(stroke
				(width 0.1)
				(type default)
			)
			(layer "B.Fab")
		)
		(fp_line
			(start -1.59893 0.47498)
			(end 0.15113 0.47498)
			(stroke
				(width 0.1)
				(type default)
			)
			(layer "B.Fab")
		)
		(pad "1" smd rect
			(at 0 0 270)
			(size 0.9398 0.9398)
			(layers "B.Cu" "B.Mask" "B.Paste")
			(net "P1V05_PCH_STBY")
		)
		(pad "2" smd rect
			(at -1.4478 0 270)
			(size 0.9398 0.9398)
			(layers "B.Cu" "B.Mask" "B.Paste")
			(net "P1V05_PCH_STBY_WM26_PLL")
		)
		(zone
			(layer "B.Cu")
			(hatch none 0.5)
			(connect_pads
				(clearance 0)
			)
			(min_thickness 0.25)
			(keepout
				(tracks not_allowed)
				(vias allowed)
				(pads allowed)
				(copperpour not_allowed)
				(footprints allowed)
			)
			(placement
				(enabled no)
				(sheetname "")
			)
			(fill
				(thermal_gap 0.5)
				(thermal_bridge_width 0.5)
				(island_removal_mode 0)
			)
			(polygon
				(pts
					(xy 408.5971 -121.5517) (xy 407.6573 -121.5517) (xy 407.6573 -121.0437) (xy 408.5971 -121.0437)
				)
			)
		)
		(zone
			(layer "B.Cu")
			(hatch none 0.5)
			(connect_pads
				(clearance 0)
			)
			(min_thickness 0.25)
			(keepout
				(tracks allowed)
				(vias not_allowed)
				(pads allowed)
				(copperpour not_allowed)
				(footprints allowed)
			)
			(placement
				(enabled no)
				(sheetname "")
			)
			(fill
				(thermal_gap 0.5)
				(thermal_bridge_width 0.5)
				(island_removal_mode 0)
			)
			(polygon
				(pts
					(xy 408.5971 -121.5517) (xy 407.6573 -121.5517) (xy 407.6573 -121.0437) (xy 408.5971 -121.0437)
				)
			)
		)
	)
	(footprint ""
		(layer "B.Cu")
		(at 473.91574 -135.41756 90)
		(property "Reference" "R1W36"
			(at 0.8382 -0.67818 90)
			(unlocked yes)
			(layer "B.SilkS")
			(effects
				(font
					(size 0.4064 0.254)
					(thickness 0.1524)
				)
				(justify left mirror)
			)
		)
		(property "Value" ""
			(at 0 0 90)
			(layer "B.Fab")
			(effects
				(font
					(size 1.27 1.27)
				)
				(justify mirror)
			)
		)
		(duplicate_pad_numbers_are_jumpers no)
		(fp_poly
			(pts
				(xy 0.2794 -0.1016) (xy -0.2794 -0.1016) (xy -0.2794 0.9906) (xy 0.2794 0.9906)
			)
			(stroke
				(width 0)
				(type default)
			)
			(fill no)
			(layer "B.CrtYd")
		)
		(fp_line
			(start 0.2794 -0.1016)
			(end 0.2794 0.9906)
			(stroke
				(width 0.1)
				(type default)
			)
			(layer "B.Fab")
		)
		(fp_line
			(start -0.2794 -0.1016)
			(end 0.2794 -0.1016)
			(stroke
				(width 0.1)
				(type default)
			)
			(layer "B.Fab")
		)
		(fp_line
			(start 0.2794 0.9906)
			(end -0.2794 0.9906)
			(stroke
				(width 0.1)
				(type default)
			)
			(layer "B.Fab")
		)
		(fp_line
			(start -0.2794 0.9906)
			(end -0.2794 -0.1016)
			(stroke
				(width 0.1)
				(type default)
			)
			(layer "B.Fab")
		)
		(pad "1" smd rect
			(at 0 0 270)
			(size 0.508 0.508)
			(layers "B.Cu" "B.Mask" "B.Paste")
			(net "P3V3_STBY")
		)
		(pad "2" smd rect
			(at 0 0.889 270)
			(size 0.508 0.508)
			(layers "B.Cu" "B.Mask" "B.Paste")
			(net "SMB_DEBUG_STBY_LVC3_SCL_CONN")
		)
		(zone
			(layer "B.Cu")
			(hatch none 0.5)
			(connect_pads
				(clearance 0)
			)
			(min_thickness 0.25)
			(keepout
				(tracks allowed)
				(vias not_allowed)
				(pads allowed)
				(copperpour not_allowed)
				(footprints allowed)
			)
			(placement
				(enabled no)
				(sheetname "")
			)
			(fill
				(thermal_gap 0.5)
				(thermal_bridge_width 0.5)
				(island_removal_mode 0)
			)
			(polygon
				(pts
					(xy 474.16974 -135.67156) (xy 474.16974 -135.16356) (xy 474.55074 -135.16356) (xy 474.55074 -135.67156)
				)
			)
		)
		(zone
			(layer "B.Cu")
			(hatch none 0.5)
			(connect_pads
				(clearance 0)
			)
			(min_thickness 0.25)
			(keepout
				(tracks not_allowed)
				(vias allowed)
				(pads allowed)
				(copperpour not_allowed)
				(footprints allowed)
			)
			(placement
				(enabled no)
				(sheetname "")
			)
			(fill
				(thermal_gap 0.5)
				(thermal_bridge_width 0.5)
				(island_removal_mode 0)
			)
			(polygon
				(pts
					(xy 474.55074 -135.67156) (xy 474.55074 -135.16356) (xy 474.16974 -135.16356) (xy 474.16974 -135.67156)
				)
			)
		)
	)
	(footprint ""
		(layer "B.Cu")
		(at 474.938344 -4.82092 90)
		(property "Reference" "R2U38"
			(at 0 0 90)
			(layer "B.SilkS")
			(hide yes)
			(effects
				(font
					(size 1.27 1.27)
				)
				(justify mirror)
			)
		)
		(property "Value" ""
			(at 0 0 90)
			(layer "B.Fab")
			(effects
				(font
					(size 1.27 1.27)
				)
				(justify mirror)
			)
		)
		(duplicate_pad_numbers_are_jumpers no)
		(fp_poly
			(pts
				(xy 0.2794 -0.1016) (xy -0.2794 -0.1016) (xy -0.2794 0.9906) (xy 0.2794 0.9906)
			)
			(stroke
				(width 0)
				(type default)
			)
			(fill no)
			(layer "B.CrtYd")
		)
		(fp_line
			(start 0.2794 -0.1016)
			(end 0.2794 0.9906)
			(stroke
				(width 0.1)
				(type default)
			)
			(layer "B.Fab")
		)
		(fp_line
			(start -0.2794 -0.1016)
			(end 0.2794 -0.1016)
			(stroke
				(width 0.1)
				(type default)
			)
			(layer "B.Fab")
		)
		(fp_line
			(start 0.2794 0.9906)
			(end -0.2794 0.9906)
			(stroke
				(width 0.1)
				(type default)
			)
			(layer "B.Fab")
		)
		(fp_line
			(start -0.2794 0.9906)
			(end -0.2794 -0.1016)
			(stroke
				(width 0.1)
				(type default)
			)
			(layer "B.Fab")
		)
		(pad "1" smd rect
			(at 0 0 270)
			(size 0.508 0.508)
			(layers "B.Cu" "B.Mask" "B.Paste")
			(net "P3V3_STBY")
		)
		(pad "2" smd rect
			(at 0 0.889 270)
			(size 0.508 0.508)
			(layers "B.Cu" "B.Mask" "B.Paste")
			(net "SMB_SENSOR_STBY_LVC3_SCL")
		)
		(zone
			(layer "B.Cu")
			(hatch none 0.5)
			(connect_pads
				(clearance 0)
			)
			(min_thickness 0.25)
			(keepout
				(tracks allowed)
				(vias not_allowed)
				(pads allowed)
				(copperpour not_allowed)
				(footprints allowed)
			)
			(placement
				(enabled no)
				(sheetname "")
			)
			(fill
				(thermal_gap 0.5)
				(thermal_bridge_width 0.5)
				(island_removal_mode 0)
			)
			(polygon
				(pts
					(xy 475.192344 -5.07492) (xy 475.192344 -4.56692) (xy 475.573344 -4.56692) (xy 475.573344 -5.07492)
				)
			)
		)
		(zone
			(layer "B.Cu")
			(hatch none 0.5)
			(connect_pads
				(clearance 0)
			)
			(min_thickness 0.25)
			(keepout
				(tracks not_allowed)
				(vias allowed)
				(pads allowed)
				(copperpour not_allowed)
				(footprints allowed)
			)
			(placement
				(enabled no)
				(sheetname "")
			)
			(fill
				(thermal_gap 0.5)
				(thermal_bridge_width 0.5)
				(island_removal_mode 0)
			)
			(polygon
				(pts
					(xy 475.573344 -5.07492) (xy 475.573344 -4.56692) (xy 475.192344 -4.56692) (xy 475.192344 -5.07492)
				)
			)
		)
	)
	(footprint ""
		(layer "B.Cu")
		(at 373.8372 -46.0756 -90)
		(property "Reference" "R2T60"
			(at 0 0 90)
			(layer "B.SilkS")
			(hide yes)
			(effects
				(font
					(size 1.27 1.27)
				)
				(justify mirror)
			)
		)
		(property "Value" ""
			(at 0 0 90)
			(layer "B.Fab")
			(effects
				(font
					(size 1.27 1.27)
				)
				(justify mirror)
			)
		)
		(duplicate_pad_numbers_are_jumpers no)
		(fp_poly
			(pts
				(xy 0.2794 -0.1016) (xy -0.2794 -0.1016) (xy -0.2794 0.9906) (xy 0.2794 0.9906)
			)
			(stroke
				(width 0)
				(type default)
			)
			(fill no)
			(layer "B.CrtYd")
		)
		(fp_line
			(start -0.2794 0.9906)
			(end -0.2794 -0.1016)
			(stroke
				(width 0.1)
				(type default)
			)
			(layer "B.Fab")
		)
		(fp_line
			(start 0.2794 0.9906)
			(end -0.2794 0.9906)
			(stroke
				(width 0.1)
				(type default)
			)
			(layer "B.Fab")
		)
		(fp_line
			(start -0.2794 -0.1016)
			(end 0.2794 -0.1016)
			(stroke
				(width 0.1)
				(type default)
			)
			(layer "B.Fab")
		)
		(fp_line
			(start 0.2794 -0.1016)
			(end 0.2794 0.9906)
			(stroke
				(width 0.1)
				(type default)
			)
			(layer "B.Fab")
		)
		(pad "1" smd rect
			(at 0 0 90)
			(size 0.508 0.508)
			(layers "B.Cu" "B.Mask" "B.Paste")
			(net "H_CPU0_PROCHOT_G_N")
		)
		(pad "2" smd rect
			(at 0 0.889 90)
			(size 0.508 0.508)
			(layers "B.Cu" "B.Mask" "B.Paste")
			(net "H_CPU0_PROCHOT_G_R_N")
		)
		(zone
			(layer "B.Cu")
			(hatch none 0.5)
			(connect_pads
				(clearance 0)
			)
			(min_thickness 0.25)
			(keepout
				(tracks not_allowed)
				(vias allowed)
				(pads allowed)
				(copperpour not_allowed)
				(footprints allowed)
			)
			(placement
				(enabled no)
				(sheetname "")
			)
			(fill
				(thermal_gap 0.5)
				(thermal_bridge_width 0.5)
				(island_removal_mode 0)
			)
			(polygon
				(pts
					(xy 373.2022 -45.8216) (xy 373.2022 -46.3296) (xy 373.5832 -46.3296) (xy 373.5832 -45.8216)
				)
			)
		)
		(zone
			(layer "B.Cu")
			(hatch none 0.5)
			(connect_pads
				(clearance 0)
			)
			(min_thickness 0.25)
			(keepout
				(tracks allowed)
				(vias not_allowed)
				(pads allowed)
				(copperpour not_allowed)
				(footprints allowed)
			)
			(placement
				(enabled no)
				(sheetname "")
			)
			(fill
				(thermal_gap 0.5)
				(thermal_bridge_width 0.5)
				(island_removal_mode 0)
			)
			(polygon
				(pts
					(xy 373.5832 -45.8216) (xy 373.5832 -46.3296) (xy 373.2022 -46.3296) (xy 373.2022 -45.8216)
				)
			)
		)
	)
)
